# SCM (Grand Teton) — schematic netlist excerpt (pin names and nets, part order shuffled) for the footprints in the layout excerpt that follows; sources: Cadence DE-HDL packaged netlist, KiCad conversion of 12092022_DA0F0TMDCD0_F0T_Management_Board_D_brd_V3_OCP.brd

R372  Q_RES  120 1% CHIP  pkg 0402LF  page 20 : A = M_BMC_DDR4_MBA1 ; B = P1V2_AUX
R689  Q_RES  33.2 1% EMPTY  pkg 0402LF  page 13 : A = IRQ_SGPIO_N ; B = IRQ_SGPIO_BMC_N

(kicad_pcb
	(version 20260206)
	(generator "pcbnew")
	(generator_version "10.0")
	(general
		(thickness 1.6)
		(legacy_teardrops no)
	)
	(paper "A4")
	(title_block
		(title "12092022_DA0F0TMDCD0_F0T_Management_Board_D_brd_V3_OCP.brd")
		(comment 1 "Grand Teton / footprints 940-941 of 1440")
	)
	(layers
		(0 "F.Cu" signal "TOP")
		(4 "In1.Cu" signal "GND")
		(6 "In2.Cu" signal "IN1")
		(8 "In3.Cu" signal "GND1")
		(10 "In4.Cu" signal "IN2")
		(12 "In5.Cu" signal "VCC")
		(14 "In6.Cu" signal "VCC1")
		(16 "In7.Cu" signal "IN3")
		(18 "In8.Cu" signal "GND2")
		(20 "In9.Cu" signal "IN4")
		(22 "In10.Cu" signal "GND3")
		(2 "B.Cu" signal "BOTTOM")
		(9 "F.Adhes" user "F.Adhesive")
		(11 "B.Adhes" user "B.Adhesive")
		(13 "F.Paste" user "Package Geometry/Pastemask Top")
		(15 "B.Paste" user "Package Geometry/Pastemask Bottom")
		(5 "F.SilkS" user "Ref Des/Silkscreen Top")
		(7 "B.SilkS" user "Ref Des/Silkscreen Bottom")
		(1 "F.Mask" user "Board Geometry/Soldermask Top")
		(3 "B.Mask" user "Board Geometry/Soldermask Bottom")
		(17 "Dwgs.User" user "User.Drawings")
		(19 "Cmts.User" user "User.Comments")
		(21 "Eco1.User" user "User.Eco1")
		(23 "Eco2.User" user "User.Eco2")
		(25 "Edge.Cuts" user "Board Geometry/Outline")
		(27 "Margin" user)
		(31 "F.CrtYd" user "Package Geometry/Place Bound Top")
		(29 "B.CrtYd" user "Package Geometry/Place Bound Bottom")
		(35 "F.Fab" user "Ref Des/Assembly Top")
		(33 "B.Fab" user "Ref Des/Assembly Bottom")
	)
	(footprint ""
		(layer "B.Cu")
		(at 85.29955 -46.463204 180)
		(property "Reference" "R372"
			(at 0 0 0)
			(layer "B.SilkS")
			(hide yes)
			(effects
				(font
					(size 1.27 1.27)
				)
				(justify mirror)
			)
		)
		(property "Value" ""
			(at 0 0 0)
			(layer "B.Fab")
			(effects
				(font
					(size 1.27 1.27)
				)
				(justify mirror)
			)
		)
		(duplicate_pad_numbers_are_jumpers no)
		(fp_line
			(start 0.7874 0.4064)
			(end 0.7874 -0.4064)
			(stroke
				(width 0.1524)
				(type default)
			)
			(layer "B.SilkS")
		)
		(fp_line
			(start 0.7874 -0.4064)
			(end -0.7874 -0.4064)
			(stroke
				(width 0.1524)
				(type default)
			)
			(layer "B.SilkS")
		)
		(fp_line
			(start -0.7874 0.4064)
			(end 0.7874 0.4064)
			(stroke
				(width 0.1524)
				(type default)
			)
			(layer "B.SilkS")
		)
		(fp_line
			(start -0.7874 -0.4064)
			(end -0.7874 0.4064)
			(stroke
				(width 0.1524)
				(type default)
			)
			(layer "B.SilkS")
		)
		(fp_line
			(start 0.67945 0.3048)
			(end 0.67945 -0.305054)
			(stroke
				(width 0.1)
				(type default)
			)
			(layer "B.Fab")
		)
		(fp_line
			(start 0.67945 -0.305054)
			(end 0.12065 -0.305054)
			(stroke
				(width 0.1)
				(type default)
			)
			(layer "B.Fab")
		)
		(fp_line
			(start 0.12065 0.3048)
			(end 0.67945 0.3048)
			(stroke
				(width 0.1)
				(type default)
			)
			(layer "B.Fab")
		)
		(fp_line
			(start 0.12065 0.2794)
			(end 0.12065 0.3048)
			(stroke
				(width 0.1)
				(type default)
			)
			(layer "B.Fab")
		)
		(fp_line
			(start 0.12065 -0.2794)
			(end -0.12065 -0.2794)
			(stroke
				(width 0.1)
				(type default)
			)
			(layer "B.Fab")
		)
		(fp_line
			(start 0.12065 -0.305054)
			(end 0.12065 -0.2794)
			(stroke
				(width 0.1)
				(type default)
			)
			(layer "B.Fab")
		)
		(fp_line
			(start -0.120396 0.3048)
			(end -0.120396 0.2794)
			(stroke
				(width 0.1)
				(type default)
			)
			(layer "B.Fab")
		)
		(fp_line
			(start -0.120396 0.2794)
			(end 0.12065 0.2794)
			(stroke
				(width 0.1)
				(type default)
			)
			(layer "B.Fab")
		)
		(fp_line
			(start -0.12065 -0.2794)
			(end -0.12065 -0.3048)
			(stroke
				(width 0.1)
				(type default)
			)
			(layer "B.Fab")
		)
		(fp_line
			(start -0.12065 -0.3048)
			(end -0.67945 -0.3048)
			(stroke
				(width 0.1)
				(type default)
			)
			(layer "B.Fab")
		)
		(fp_line
			(start -0.67945 0.3048)
			(end -0.120396 0.3048)
			(stroke
				(width 0.1)
				(type default)
			)
			(layer "B.Fab")
		)
		(fp_line
			(start -0.67945 -0.3048)
			(end -0.67945 0.3048)
			(stroke
				(width 0.1)
				(type default)
			)
			(layer "B.Fab")
		)
		(pad "1" smd circle
			(at 0.40005 0)
			(size 0 0)
			(layers "B.Cu" "B.Mask" "B.Paste")
			(net "M_BMC_DDR4_MBA1")
		)
		(pad "2" smd circle
			(at -0.40005 0)
			(size 0 0)
			(layers "B.Cu" "B.Mask" "B.Paste")
			(net "P1V2_AUX")
		)
	)
	(footprint ""
		(layer "B.Cu")
		(at 41.91 -42.037 180)
		(property "Reference" "R689"
			(at 0 0 0)
			(layer "B.SilkS")
			(hide yes)
			(effects
				(font
					(size 1.27 1.27)
				)
				(justify mirror)
			)
		)
		(property "Value" ""
			(at 0 0 0)
			(layer "B.Fab")
			(effects
				(font
					(size 1.27 1.27)
				)
				(justify mirror)
			)
		)
		(duplicate_pad_numbers_are_jumpers no)
		(fp_line
			(start 0.7874 0.4064)
			(end 0.7874 -0.4064)
			(stroke
				(width 0.1524)
				(type default)
			)
			(layer "B.SilkS")
		)
		(fp_line
			(start 0.7874 -0.4064)
			(end -0.7874 -0.4064)
			(stroke
				(width 0.1524)
				(type default)
			)
			(layer "B.SilkS")
		)
		(fp_line
			(start -0.7874 0.4064)
			(end 0.7874 0.4064)
			(stroke
				(width 0.1524)
				(type default)
			)
			(layer "B.SilkS")
		)
		(fp_line
			(start -0.7874 -0.4064)
			(end -0.7874 0.4064)
			(stroke
				(width 0.1524)
				(type default)
			)
			(layer "B.SilkS")
		)
		(fp_line
			(start 0.67945 0.3048)
			(end 0.67945 -0.305054)
			(stroke
				(width 0.1)
				(type default)
			)
			(layer "B.Fab")
		)
		(fp_line
			(start 0.67945 -0.305054)
			(end 0.12065 -0.305054)
			(stroke
				(width 0.1)
				(type default)
			)
			(layer "B.Fab")
		)
		(fp_line
			(start 0.12065 0.3048)
			(end 0.67945 0.3048)
			(stroke
				(width 0.1)
				(type default)
			)
			(layer "B.Fab")
		)
		(fp_line
			(start 0.12065 0.2794)
			(end 0.12065 0.3048)
			(stroke
				(width 0.1)
				(type default)
			)
			(layer "B.Fab")
		)
		(fp_line
			(start 0.12065 -0.2794)
			(end -0.12065 -0.2794)
			(stroke
				(width 0.1)
				(type default)
			)
			(layer "B.Fab")
		)
		(fp_line
			(start 0.12065 -0.305054)
			(end 0.12065 -0.2794)
			(stroke
				(width 0.1)
				(type default)
			)
			(layer "B.Fab")
		)
		(fp_line
			(start -0.120396 0.3048)
			(end -0.120396 0.2794)
			(stroke
				(width 0.1)
				(type default)
			)
			(layer "B.Fab")
		)
		(fp_line
			(start -0.120396 0.2794)
			(end 0.12065 0.2794)
			(stroke
				(width 0.1)
				(type default)
			)
			(layer "B.Fab")
		)
		(fp_line
			(start -0.12065 -0.2794)
			(end -0.12065 -0.3048)
			(stroke
				(width 0.1)
				(type default)
			)
			(layer "B.Fab")
		)
		(fp_line
			(start -0.12065 -0.3048)
			(end -0.67945 -0.3048)
			(stroke
				(width 0.1)
				(type default)
			)
			(layer "B.Fab")
		)
		(fp_line
			(start -0.67945 0.3048)
			(end -0.120396 0.3048)
			(stroke
				(width 0.1)
				(type default)
			)
			(layer "B.Fab")
		)
		(fp_line
			(start -0.67945 -0.3048)
			(end -0.67945 0.3048)
			(stroke
				(width 0.1)
				(type default)
			)
			(layer "B.Fab")
		)
		(pad "1" smd circle
			(at 0.40005 0)
			(size 0 0)
			(layers "B.Cu" "B.Mask" "B.Paste")
			(net "IRQ_SGPIO_N")
		)
		(pad "2" smd circle
			(at -0.40005 0)
			(size 0 0)
			(layers "B.Cu" "B.Mask" "B.Paste")
			(net "IRQ_SGPIO_BMC_N")
		)
	)
)
